(kicad_pcb
	(version 20260206)
	(generator "pcbnew")
	(generator_version "10.0")
	(general
		(thickness 1.6)
		(legacy_teardrops no)
	)
	(paper "A4")
	(title_block
		(title "peb — Lightning_PEB_BRD.brd")
		(comment 1 "Lightning (Wiwynn / Facebook NVMe JBOF) / footprints 1060-1063 of 2563")
	)
	(layers
		(0 "F.Cu" signal "TOP")
		(4 "In1.Cu" signal "L2GND")
		(6 "In2.Cu" signal "L3")
		(8 "In3.Cu" signal "L4VCC")
		(10 "In4.Cu" signal "L5VCC")
		(12 "In5.Cu" signal "L6")
		(14 "In6.Cu" signal "L7GND")
		(2 "B.Cu" signal "BOTTOM")
		(9 "F.Adhes" user "F.Adhesive")
		(11 "B.Adhes" user "B.Adhesive")
		(13 "F.Paste" user "Package Geometry/Pastemask Top")
		(15 "B.Paste" user "Package Geometry/Pastemask Bottom")
		(5 "F.SilkS" user "Ref Des/Silkscreen Top")
		(7 "B.SilkS" user "Ref Des/Silkscreen Bottom")
		(1 "F.Mask" user "Board Geometry/Soldermask Top")
		(3 "B.Mask" user "Board Geometry/Soldermask Bottom")
		(17 "Dwgs.User" user "User.Drawings")
		(19 "Cmts.User" user "User.Comments")
		(21 "Eco1.User" user "User.Eco1")
		(23 "Eco2.User" user "User.Eco2")
		(25 "Edge.Cuts" user "Board Geometry/Outline")
		(27 "Margin" user)
		(31 "F.CrtYd" user "Package Geometry/Place Bound Top")
		(29 "B.CrtYd" user "Package Geometry/Place Bound Bottom")
		(35 "F.Fab" user "Ref Des/Assembly Top")
		(33 "B.Fab" user "Ref Des/Assembly Bottom")
	)
	(footprint ""
		(layer "F.Cu")
		(at 136.386062 -74.43724 180)
		(property "Reference" "R958"
			(at 0 0 180)
			(layer "F.SilkS")
			(hide yes)
			(effects
				(font
					(size 1.27 1.27)
				)
			)
		)
		(property "Value" "82R2F-4-GP"
			(at 0.064008 -3.993896 180)
			(unlocked yes)
			(layer "F.Fab")
			(hide yes)
			(effects
				(font
					(size 1.016 1.016)
					(thickness 0.1524)
				)
			)
		)
		(property "Device Type" "R402H16"
			(at 0.064008 -5.517896 180)
			(unlocked yes)
			(layer "F.Fab")
			(hide yes)
			(effects
				(font
					(size 1.016 1.016)
					(thickness 0.1524)
				)
			)
		)
		(duplicate_pad_numbers_are_jumpers no)
		(fp_line
			(start 0.508 -0.9398)
			(end -0.508 -0.9398)
			(stroke
				(width 0.1524)
				(type default)
			)
			(layer "F.SilkS")
		)
		(fp_line
			(start -0.508 -0.9398)
			(end -0.508 0.9398)
			(stroke
				(width 0.1524)
				(type default)
			)
			(layer "F.SilkS")
		)
		(fp_rect
			(start -0.508 0.9398)
			(end 0.508 -0.9398)
			(stroke
				(width 0)
				(type default)
			)
			(fill no)
			(layer "F.CrtYd")
		)
		(fp_rect
			(start -0.508 0.9398)
			(end 0.508 -0.9398)
			(stroke
				(width 0)
				(type default)
			)
			(fill no)
			(layer "F.Fab")
		)
		(pad "1" smd custom
			(at 0 -0.4445 180)
			(size 0.1397 0.1397)
			(layers "F.Cu" "F.Mask" "F.Paste")
			(net "SPI_CLK0_R")
			(options
				(clearance outline)
				(anchor circle)
			)
			(primitives
				(gr_poly
					(pts
						(arc
							(start -0.1778 -0.2794)
							(mid -0.249642 -0.249642)
							(end -0.2794 -0.1778)
						)
						(arc
							(start -0.2794 0.1778)
							(mid -0.249642 0.249642)
							(end -0.1778 0.2794)
						)
						(arc
							(start 0.1778 0.2794)
							(mid 0.249642 0.249642)
							(end 0.2794 0.1778)
						)
						(arc
							(start 0.2794 -0.1778)
							(mid 0.249642 -0.249642)
							(end 0.1778 -0.2794)
						)
					)
					(width 0)
					(fill yes)
				)
			)
		)
		(pad "2" smd custom
			(at 0 0.4445 180)
			(size 0.1397 0.1397)
			(layers "F.Cu" "F.Mask" "F.Paste")
			(net "SPI_CLK0")
			(options
				(clearance outline)
				(anchor circle)
			)
			(primitives
				(gr_poly
					(pts
						(arc
							(start -0.1778 -0.2794)
							(mid -0.249642 -0.249642)
							(end -0.2794 -0.1778)
						)
						(arc
							(start -0.2794 0.1778)
							(mid -0.249642 0.249642)
							(end -0.1778 0.2794)
						)
						(arc
							(start 0.1778 0.2794)
							(mid 0.249642 0.249642)
							(end 0.2794 0.1778)
						)
						(arc
							(start 0.2794 -0.1778)
							(mid 0.249642 -0.249642)
							(end 0.1778 -0.2794)
						)
					)
					(width 0)
					(fill yes)
				)
			)
		)
	)
	(footprint ""
		(layer "F.Cu")
		(at 25.6286 -186.0042 90)
		(property "Reference" "R967"
			(at 0 0 90)
			(layer "F.SilkS")
			(hide yes)
			(effects
				(font
					(size 1.27 1.27)
				)
			)
		)
		(property "Value" "0R2J-2-GP"
			(at 0.064008 -3.993896 90)
			(unlocked yes)
			(layer "F.Fab")
			(hide yes)
			(effects
				(font
					(size 1.016 1.016)
					(thickness 0.1524)
				)
			)
		)
		(property "Device Type" "R402H16"
			(at 0.064008 -5.517896 90)
			(unlocked yes)
			(layer "F.Fab")
			(hide yes)
			(effects
				(font
					(size 1.016 1.016)
					(thickness 0.1524)
				)
			)
		)
		(duplicate_pad_numbers_are_jumpers no)
		(fp_line
			(start 0.508 -0.9398)
			(end -0.508 -0.9398)
			(stroke
				(width 0.1524)
				(type default)
			)
			(layer "F.SilkS")
		)
		(fp_line
			(start -0.508 -0.9398)
			(end -0.508 0.9398)
			(stroke
				(width 0.1524)
				(type default)
			)
			(layer "F.SilkS")
		)
		(fp_rect
			(start -0.508 0.9398)
			(end 0.508 -0.9398)
			(stroke
				(width 0)
				(type default)
			)
			(fill no)
			(layer "F.CrtYd")
		)
		(fp_rect
			(start -0.508 0.9398)
			(end 0.508 -0.9398)
			(stroke
				(width 0)
				(type default)
			)
			(fill no)
			(layer "F.Fab")
		)
		(pad "1" smd custom
			(at 0 -0.4445 90)
			(size 0.1397 0.1397)
			(layers "F.Cu" "F.Mask" "F.Paste")
			(net "BMC_I2C5_D_PEB_SCL")
			(options
				(clearance outline)
				(anchor circle)
			)
			(primitives
				(gr_poly
					(pts
						(arc
							(start -0.1778 -0.2794)
							(mid -0.249642 -0.249642)
							(end -0.2794 -0.1778)
						)
						(arc
							(start -0.2794 0.1778)
							(mid -0.249642 0.249642)
							(end -0.1778 0.2794)
						)
						(arc
							(start 0.1778 0.2794)
							(mid 0.249642 0.249642)
							(end 0.2794 0.1778)
						)
						(arc
							(start 0.2794 -0.1778)
							(mid 0.249642 -0.249642)
							(end 0.1778 -0.2794)
						)
					)
					(width 0)
					(fill yes)
				)
			)
		)
		(pad "2" smd custom
			(at 0 0.4445 90)
			(size 0.1397 0.1397)
			(layers "F.Cu" "F.Mask" "F.Paste")
			(net "BMC_I2C5_SCL_R")
			(options
				(clearance outline)
				(anchor circle)
			)
			(primitives
				(gr_poly
					(pts
						(arc
							(start -0.1778 -0.2794)
							(mid -0.249642 -0.249642)
							(end -0.2794 -0.1778)
						)
						(arc
							(start -0.2794 0.1778)
							(mid -0.249642 0.249642)
							(end -0.1778 0.2794)
						)
						(arc
							(start 0.1778 0.2794)
							(mid 0.249642 0.249642)
							(end 0.2794 0.1778)
						)
						(arc
							(start 0.2794 -0.1778)
							(mid 0.249642 -0.249642)
							(end 0.1778 -0.2794)
						)
					)
					(width 0)
					(fill yes)
				)
			)
		)
	)
	(footprint ""
		(layer "F.Cu")
		(at 7.581392 -78.961488 90)
		(property "Reference" "R397"
			(at 0 0 90)
			(layer "F.SilkS")
			(hide yes)
			(effects
				(font
					(size 1.27 1.27)
				)
			)
		)
		(property "Value" "10KR2F-2-GP"
			(at 0.064008 -3.993896 90)
			(unlocked yes)
			(layer "F.Fab")
			(hide yes)
			(effects
				(font
					(size 1.016 1.016)
					(thickness 0.1524)
				)
			)
		)
		(property "Device Type" "R402H16"
			(at 0.064008 -5.517896 90)
			(unlocked yes)
			(layer "F.Fab")
			(hide yes)
			(effects
				(font
					(size 1.016 1.016)
					(thickness 0.1524)
				)
			)
		)
		(duplicate_pad_numbers_are_jumpers no)
		(fp_line
			(start 0.508 -0.9398)
			(end -0.508 -0.9398)
			(stroke
				(width 0.1524)
				(type default)
			)
			(layer "F.SilkS")
		)
		(fp_line
			(start -0.508 -0.9398)
			(end -0.508 0.9398)
			(stroke
				(width 0.1524)
				(type default)
			)
			(layer "F.SilkS")
		)
		(fp_rect
			(start -0.508 0.9398)
			(end 0.508 -0.9398)
			(stroke
				(width 0)
				(type default)
			)
			(fill no)
			(layer "F.CrtYd")
		)
		(fp_rect
			(start -0.508 0.9398)
			(end 0.508 -0.9398)
			(stroke
				(width 0)
				(type default)
			)
			(fill no)
			(layer "F.Fab")
		)
		(pad "1" smd custom
			(at 0 -0.4445 90)
			(size 0.1397 0.1397)
			(layers "F.Cu" "F.Mask" "F.Paste")
			(net "P3V3_STBY")
			(options
				(clearance outline)
				(anchor circle)
			)
			(primitives
				(gr_poly
					(pts
						(arc
							(start -0.1778 -0.2794)
							(mid -0.249642 -0.249642)
							(end -0.2794 -0.1778)
						)
						(arc
							(start -0.2794 0.1778)
							(mid -0.249642 0.249642)
							(end -0.1778 0.2794)
						)
						(arc
							(start 0.1778 0.2794)
							(mid 0.249642 0.249642)
							(end 0.2794 0.1778)
						)
						(arc
							(start 0.2794 -0.1778)
							(mid 0.249642 -0.249642)
							(end 0.1778 -0.2794)
						)
					)
					(width 0)
					(fill yes)
				)
			)
		)
		(pad "2" smd custom
			(at 0 0.4445 90)
			(size 0.1397 0.1397)
			(layers "F.Cu" "F.Mask" "F.Paste")
			(net "LAN_SMB_CLK")
			(options
				(clearance outline)
				(anchor circle)
			)
			(primitives
				(gr_poly
					(pts
						(arc
							(start -0.1778 -0.2794)
							(mid -0.249642 -0.249642)
							(end -0.2794 -0.1778)
						)
						(arc
							(start -0.2794 0.1778)
							(mid -0.249642 0.249642)
							(end -0.1778 0.2794)
						)
						(arc
							(start 0.1778 0.2794)
							(mid 0.249642 0.249642)
							(end 0.2794 0.1778)
						)
						(arc
							(start 0.2794 -0.1778)
							(mid 0.249642 -0.249642)
							(end 0.1778 -0.2794)
						)
					)
					(width 0)
					(fill yes)
				)
			)
		)
	)
	(footprint ""
		(layer "F.Cu")
		(at 345.60002 -203.499974)
		(property "Reference" ""
			(at 0 0 0)
			(layer "F.SilkS")
			(hide yes)
			(effects
				(font
					(size 1.27 1.27)
				)
			)
		)
		(property "Value" "*"
			(at -0.1524 -7.3914 0)
			(unlocked yes)
			(layer "F.Fab")
			(hide yes)
			(effects
				(font
					(size 1.016 1.016)
					(thickness 0.1524)
				)
			)
		)
		(duplicate_pad_numbers_are_jumpers no)
		(fp_poly
			(pts
				(arc
					(start 4.3053 0)
					(mid -4.3053 0)
					(end 4.3053 0)
				)
			)
			(stroke
				(width 0)
				(type default)
			)
			(fill no)
			(layer "B.CrtYd")
		)
		(fp_poly
			(pts
				(arc
					(start 4.3053 0)
					(mid -4.3053 0)
					(end 4.3053 0)
				)
			)
			(stroke
				(width 0)
				(type default)
			)
			(fill no)
			(layer "F.CrtYd")
		)
		(fp_poly
			(pts
				(arc
					(start 4.3053 0)
					(mid -4.3053 0)
					(end 4.3053 0)
				)
			)
			(stroke
				(width 0)
				(type default)
			)
			(fill no)
			(layer "B.Fab")
		)
		(fp_poly
			(pts
				(arc
					(start 4.3053 0)
					(mid -4.3053 0)
					(end 4.3053 0)
				)
			)
			(stroke
				(width 0)
				(type default)
			)
			(fill no)
			(layer "F.Fab")
		)
		(pad "1" thru_hole circle
			(at 0 0)
			(size 8.001 8.001)
			(drill 3.81)
			(layers "*.Cu" "*.Mask")
			(remove_unused_layers no)
			(net "Net_115")
			(clearance -1.5875)
			(thermal_gap 0.3048)
			(padstack
				(mode front_inner_back)
				(layer "Inner"
					(shape circle)
					(size 4.2164 4.2164)
					(clearance 0.3048)
				)
				(layer "B.Cu"
					(shape circle)
					(size 8.001 8.001)
					(clearance -1.5875)
				)
			)
		)
	)
)
